(kicad_pcb
	(version 20260206)
	(generator "pcbnew")
	(generator_version "10.0")
	(general
		(thickness 1.6)
		(legacy_teardrops no)
	)
	(paper "A4")
	(title_block
		(title "01162023_DA0F0TEBIF0_F0T_Expander_BD_F_brd_V02_OCP.brd")
		(comment 1 "Grand Teton / footprints 1094-1099 of 9728")
	)
	(layers
		(0 "F.Cu" signal "TOP")
		(4 "In1.Cu" signal "GND")
		(6 "In2.Cu" signal "VCC")
		(8 "In3.Cu" signal "VCC1")
		(10 "In4.Cu" signal "GND1")
		(12 "In5.Cu" signal "IN1")
		(14 "In6.Cu" signal "GND2")
		(16 "In7.Cu" signal "IN2")
		(18 "In8.Cu" signal "GND3")
		(20 "In9.Cu" signal "IN3")
		(22 "In10.Cu" signal "GND4")
		(24 "In11.Cu" signal "IN4")
		(26 "In12.Cu" signal "GND5")
		(28 "In13.Cu" signal "IN5")
		(30 "In14.Cu" signal "GND6")
		(32 "In15.Cu" signal "IN6")
		(34 "In16.Cu" signal "GND7")
		(2 "B.Cu" signal "BOTTOM")
		(9 "F.Adhes" user "F.Adhesive")
		(11 "B.Adhes" user "B.Adhesive")
		(13 "F.Paste" user "Package Geometry/Pastemask Top")
		(15 "B.Paste" user "Package Geometry/Pastemask Bottom")
		(5 "F.SilkS" user "Ref Des/Silkscreen Top")
		(7 "B.SilkS" user "Ref Des/Silkscreen Bottom")
		(1 "F.Mask" user "Board Geometry/Soldermask Top")
		(3 "B.Mask" user "Board Geometry/Soldermask Bottom")
		(17 "Dwgs.User" user "User.Drawings")
		(19 "Cmts.User" user "User.Comments")
		(21 "Eco1.User" user "User.Eco1")
		(23 "Eco2.User" user "User.Eco2")
		(25 "Edge.Cuts" user "Board Geometry/Outline")
		(27 "Margin" user)
		(31 "F.CrtYd" user "Package Geometry/Place Bound Top")
		(29 "B.CrtYd" user "Package Geometry/Place Bound Bottom")
		(35 "F.Fab" user "Ref Des/Assembly Top")
		(33 "B.Fab" user "Ref Des/Assembly Bottom")
	)
	(footprint ""
		(layer "F.Cu")
		(at 238.21898 -224.48266 180)
		(property "Reference" "C4437"
			(at 0 0 180)
			(layer "F.SilkS")
			(hide yes)
			(effects
				(font
					(size 1.27 1.27)
				)
			)
		)
		(property "Value" ""
			(at 0 0 180)
			(layer "F.Fab")
			(effects
				(font
					(size 1.27 1.27)
				)
			)
		)
		(duplicate_pad_numbers_are_jumpers no)
		(fp_line
			(start 0.7874 0.4064)
			(end -0.7874 0.4064)
			(stroke
				(width 0.1524)
				(type default)
			)
			(layer "F.SilkS")
		)
		(fp_line
			(start 0.7874 -0.4064)
			(end 0.7874 0.4064)
			(stroke
				(width 0.1524)
				(type default)
			)
			(layer "F.SilkS")
		)
		(fp_line
			(start -0.7874 0.4064)
			(end -0.7874 -0.4064)
			(stroke
				(width 0.1524)
				(type default)
			)
			(layer "F.SilkS")
		)
		(fp_line
			(start -0.7874 -0.4064)
			(end 0.7874 -0.4064)
			(stroke
				(width 0.1524)
				(type default)
			)
			(layer "F.SilkS")
		)
		(fp_line
			(start 0.67945 0.3048)
			(end 0.120396 0.3048)
			(stroke
				(width 0.1)
				(type default)
			)
			(layer "F.Fab")
		)
		(fp_line
			(start 0.67945 -0.3048)
			(end 0.67945 0.3048)
			(stroke
				(width 0.1)
				(type default)
			)
			(layer "F.Fab")
		)
		(fp_line
			(start 0.12065 -0.2794)
			(end 0.12065 -0.3048)
			(stroke
				(width 0.1)
				(type default)
			)
			(layer "F.Fab")
		)
		(fp_line
			(start 0.12065 -0.3048)
			(end 0.67945 -0.3048)
			(stroke
				(width 0.1)
				(type default)
			)
			(layer "F.Fab")
		)
		(fp_line
			(start 0.120396 0.3048)
			(end 0.120396 0.2794)
			(stroke
				(width 0.1)
				(type default)
			)
			(layer "F.Fab")
		)
		(fp_line
			(start 0.120396 0.2794)
			(end -0.12065 0.2794)
			(stroke
				(width 0.1)
				(type default)
			)
			(layer "F.Fab")
		)
		(fp_line
			(start -0.12065 0.3048)
			(end -0.67945 0.3048)
			(stroke
				(width 0.1)
				(type default)
			)
			(layer "F.Fab")
		)
		(fp_line
			(start -0.12065 0.2794)
			(end -0.12065 0.3048)
			(stroke
				(width 0.1)
				(type default)
			)
			(layer "F.Fab")
		)
		(fp_line
			(start -0.12065 -0.2794)
			(end 0.12065 -0.2794)
			(stroke
				(width 0.1)
				(type default)
			)
			(layer "F.Fab")
		)
		(fp_line
			(start -0.12065 -0.305054)
			(end -0.12065 -0.2794)
			(stroke
				(width 0.1)
				(type default)
			)
			(layer "F.Fab")
		)
		(fp_line
			(start -0.67945 0.3048)
			(end -0.67945 -0.305054)
			(stroke
				(width 0.1)
				(type default)
			)
			(layer "F.Fab")
		)
		(fp_line
			(start -0.67945 -0.305054)
			(end -0.12065 -0.305054)
			(stroke
				(width 0.1)
				(type default)
			)
			(layer "F.Fab")
		)
		(pad "1" smd circle
			(at -0.40005 0 180)
			(size 0 0)
			(layers "F.Cu" "F.Mask" "F.Paste")
			(net "P1V8_PLL0_PEX3_SCALED")
		)
		(pad "2" smd circle
			(at 0.40005 0 180)
			(size 0 0)
			(layers "F.Cu" "F.Mask" "F.Paste")
			(net "GND")
		)
	)
	(footprint ""
		(layer "F.Cu")
		(at 10.045446 -255.046734 -90)
		(property "Reference" "R6463"
			(at 0 0 270)
			(layer "F.SilkS")
			(hide yes)
			(effects
				(font
					(size 1.27 1.27)
				)
			)
		)
		(property "Value" ""
			(at 0 0 270)
			(layer "F.Fab")
			(effects
				(font
					(size 1.27 1.27)
				)
			)
		)
		(duplicate_pad_numbers_are_jumpers no)
		(fp_line
			(start -0.7874 0.4064)
			(end -0.7874 -0.4064)
			(stroke
				(width 0.1524)
				(type default)
			)
			(layer "F.SilkS")
		)
		(fp_line
			(start 0.7874 0.4064)
			(end -0.7874 0.4064)
			(stroke
				(width 0.1524)
				(type default)
			)
			(layer "F.SilkS")
		)
		(fp_line
			(start -0.7874 -0.4064)
			(end 0.7874 -0.4064)
			(stroke
				(width 0.1524)
				(type default)
			)
			(layer "F.SilkS")
		)
		(fp_line
			(start 0.7874 -0.4064)
			(end 0.7874 0.4064)
			(stroke
				(width 0.1524)
				(type default)
			)
			(layer "F.SilkS")
		)
		(fp_line
			(start -0.67945 0.3048)
			(end -0.67945 -0.305054)
			(stroke
				(width 0.1)
				(type default)
			)
			(layer "F.Fab")
		)
		(fp_line
			(start -0.12065 0.3048)
			(end -0.67945 0.3048)
			(stroke
				(width 0.1)
				(type default)
			)
			(layer "F.Fab")
		)
		(fp_line
			(start 0.120396 0.3048)
			(end 0.120396 0.2794)
			(stroke
				(width 0.1)
				(type default)
			)
			(layer "F.Fab")
		)
		(fp_line
			(start 0.67945 0.3048)
			(end 0.120396 0.3048)
			(stroke
				(width 0.1)
				(type default)
			)
			(layer "F.Fab")
		)
		(fp_line
			(start -0.12065 0.2794)
			(end -0.12065 0.3048)
			(stroke
				(width 0.1)
				(type default)
			)
			(layer "F.Fab")
		)
		(fp_line
			(start 0.120396 0.2794)
			(end -0.12065 0.2794)
			(stroke
				(width 0.1)
				(type default)
			)
			(layer "F.Fab")
		)
		(fp_line
			(start -0.12065 -0.2794)
			(end 0.12065 -0.2794)
			(stroke
				(width 0.1)
				(type default)
			)
			(layer "F.Fab")
		)
		(fp_line
			(start 0.12065 -0.2794)
			(end 0.12065 -0.3048)
			(stroke
				(width 0.1)
				(type default)
			)
			(layer "F.Fab")
		)
		(fp_line
			(start 0.12065 -0.3048)
			(end 0.67945 -0.3048)
			(stroke
				(width 0.1)
				(type default)
			)
			(layer "F.Fab")
		)
		(fp_line
			(start 0.67945 -0.3048)
			(end 0.67945 0.3048)
			(stroke
				(width 0.1)
				(type default)
			)
			(layer "F.Fab")
		)
		(fp_line
			(start -0.67945 -0.305054)
			(end -0.12065 -0.305054)
			(stroke
				(width 0.1)
				(type default)
			)
			(layer "F.Fab")
		)
		(fp_line
			(start -0.12065 -0.305054)
			(end -0.12065 -0.2794)
			(stroke
				(width 0.1)
				(type default)
			)
			(layer "F.Fab")
		)
		(pad "1" smd circle
			(at -0.40005 0 270)
			(size 0 0)
			(layers "F.Cu" "F.Mask" "F.Paste")
			(net "P1V25_SERDES_VDDPLL_PEX0")
		)
		(pad "2" smd circle
			(at 0.40005 0 270)
			(size 0 0)
			(layers "F.Cu" "F.Mask" "F.Paste")
			(net "P1V25_SERDES_VDDPLL_PEX0_C2")
		)
	)
	(footprint ""
		(layer "F.Cu")
		(at 209.166206 -306.074572 90)
		(property "Reference" "R4177"
			(at 0 0 90)
			(layer "F.SilkS")
			(hide yes)
			(effects
				(font
					(size 1.27 1.27)
				)
			)
		)
		(property "Value" ""
			(at 0 0 90)
			(layer "F.Fab")
			(effects
				(font
					(size 1.27 1.27)
				)
			)
		)
		(duplicate_pad_numbers_are_jumpers no)
		(fp_line
			(start 0.7874 -0.4064)
			(end 0.7874 0.4064)
			(stroke
				(width 0.1524)
				(type default)
			)
			(layer "F.SilkS")
		)
		(fp_line
			(start -0.7874 -0.4064)
			(end 0.7874 -0.4064)
			(stroke
				(width 0.1524)
				(type default)
			)
			(layer "F.SilkS")
		)
		(fp_line
			(start 0.7874 0.4064)
			(end -0.7874 0.4064)
			(stroke
				(width 0.1524)
				(type default)
			)
			(layer "F.SilkS")
		)
		(fp_line
			(start -0.7874 0.4064)
			(end -0.7874 -0.4064)
			(stroke
				(width 0.1524)
				(type default)
			)
			(layer "F.SilkS")
		)
		(fp_line
			(start -0.12065 -0.305054)
			(end -0.12065 -0.2794)
			(stroke
				(width 0.1)
				(type default)
			)
			(layer "F.Fab")
		)
		(fp_line
			(start -0.67945 -0.305054)
			(end -0.12065 -0.305054)
			(stroke
				(width 0.1)
				(type default)
			)
			(layer "F.Fab")
		)
		(fp_line
			(start 0.67945 -0.3048)
			(end 0.67945 0.3048)
			(stroke
				(width 0.1)
				(type default)
			)
			(layer "F.Fab")
		)
		(fp_line
			(start 0.12065 -0.3048)
			(end 0.67945 -0.3048)
			(stroke
				(width 0.1)
				(type default)
			)
			(layer "F.Fab")
		)
		(fp_line
			(start 0.12065 -0.2794)
			(end 0.12065 -0.3048)
			(stroke
				(width 0.1)
				(type default)
			)
			(layer "F.Fab")
		)
		(fp_line
			(start -0.12065 -0.2794)
			(end 0.12065 -0.2794)
			(stroke
				(width 0.1)
				(type default)
			)
			(layer "F.Fab")
		)
		(fp_line
			(start 0.120396 0.2794)
			(end -0.12065 0.2794)
			(stroke
				(width 0.1)
				(type default)
			)
			(layer "F.Fab")
		)
		(fp_line
			(start -0.12065 0.2794)
			(end -0.12065 0.3048)
			(stroke
				(width 0.1)
				(type default)
			)
			(layer "F.Fab")
		)
		(fp_line
			(start 0.67945 0.3048)
			(end 0.120396 0.3048)
			(stroke
				(width 0.1)
				(type default)
			)
			(layer "F.Fab")
		)
		(fp_line
			(start 0.120396 0.3048)
			(end 0.120396 0.2794)
			(stroke
				(width 0.1)
				(type default)
			)
			(layer "F.Fab")
		)
		(fp_line
			(start -0.12065 0.3048)
			(end -0.67945 0.3048)
			(stroke
				(width 0.1)
				(type default)
			)
			(layer "F.Fab")
		)
		(fp_line
			(start -0.67945 0.3048)
			(end -0.67945 -0.305054)
			(stroke
				(width 0.1)
				(type default)
			)
			(layer "F.Fab")
		)
		(pad "1" smd circle
			(at -0.40005 0 90)
			(size 0 0)
			(layers "F.Cu" "F.Mask" "F.Paste")
			(net "PEX1_EXT_GPIO_LATCH_N")
		)
		(pad "2" smd circle
			(at 0.40005 0 90)
			(size 0 0)
			(layers "F.Cu" "F.Mask" "F.Paste")
			(net "P1V8_PEX")
		)
	)
	(footprint ""
		(layer "F.Cu")
		(at 459.067916 -277.91537 180)
		(property "Reference" "U95"
			(at -2.934462 -5.574792 0)
			(unlocked yes)
			(layer "F.SilkS")
			(effects
				(font
					(size 0.7874 0.5842)
					(thickness 0.1524)
				)
			)
		)
		(property "Value" ""
			(at 0 0 180)
			(layer "F.Fab")
			(effects
				(font
					(size 1.27 1.27)
				)
			)
		)
		(duplicate_pad_numbers_are_jumpers no)
		(fp_line
			(start 1.500124 1.500124)
			(end 1.004062 1.500124)
			(stroke
				(width 0.1524)
				(type default)
			)
			(layer "F.SilkS")
		)
		(fp_line
			(start 1.500124 1.004062)
			(end 1.500124 1.500124)
			(stroke
				(width 0.1524)
				(type default)
			)
			(layer "F.SilkS")
		)
		(fp_line
			(start 1.500124 -1.500124)
			(end 1.500124 -1.004062)
			(stroke
				(width 0.1524)
				(type default)
			)
			(layer "F.SilkS")
		)
		(fp_line
			(start 1.004062 -1.500124)
			(end 1.500124 -1.500124)
			(stroke
				(width 0.1524)
				(type default)
			)
			(layer "F.SilkS")
		)
		(fp_line
			(start -1.004062 1.500124)
			(end -1.500124 1.500124)
			(stroke
				(width 0.1524)
				(type default)
			)
			(layer "F.SilkS")
		)
		(fp_line
			(start -1.500124 1.500124)
			(end -1.500124 1.004062)
			(stroke
				(width 0.1524)
				(type default)
			)
			(layer "F.SilkS")
		)
		(fp_line
			(start -1.500124 -1.004062)
			(end -1.500124 -1.500124)
			(stroke
				(width 0.1524)
				(type default)
			)
			(layer "F.SilkS")
		)
		(fp_line
			(start -1.500124 -1.500124)
			(end -1.004062 -1.500124)
			(stroke
				(width 0.1524)
				(type default)
			)
			(layer "F.SilkS")
		)
		(fp_poly
			(pts
				(xy -1.308608 -2.198116) (xy -2.324608 -2.198116) (xy -1.816608 -1.182116)
			)
			(stroke
				(width 0)
				(type default)
			)
			(fill yes)
			(layer "F.SilkS")
		)
		(fp_line
			(start 1.500124 1.500124)
			(end -1.500124 1.500124)
			(stroke
				(width 0.1)
				(type default)
			)
			(layer "F.Fab")
		)
		(fp_line
			(start 1.500124 -1.500124)
			(end 1.500124 1.500124)
			(stroke
				(width 0.1)
				(type default)
			)
			(layer "F.Fab")
		)
		(fp_line
			(start -1.500124 1.500124)
			(end -1.500124 -1.500124)
			(stroke
				(width 0.1)
				(type default)
			)
			(layer "F.Fab")
		)
		(fp_line
			(start -1.500124 -1.500124)
			(end 1.500124 -1.500124)
			(stroke
				(width 0.1)
				(type default)
			)
			(layer "F.Fab")
		)
		(fp_poly
			(pts
				(xy -2.847848 -1.258062) (xy -2.847848 -0.242062) (xy -1.831848 -0.750062)
			)
			(stroke
				(width 0)
				(type default)
			)
			(fill yes)
			(layer "F.Fab")
		)
		(pad "1" smd rect
			(at -1.400048 -0.750062 90)
			(size 0.2286 0.6096)
			(layers "F.Cu" "F.Mask" "F.Paste")
			(net "PEX3_P1V25_ADC_A1")
		)
		(pad "2" smd rect
			(at -1.400048 -0.249936 90)
			(size 0.2286 0.6096)
			(layers "F.Cu" "F.Mask" "F.Paste")
			(net "PEX3_P1V25_ADC_A0")
		)
		(pad "3" smd rect
			(at -1.400048 0.249936 90)
			(size 0.2286 0.6096)
			(layers "F.Cu" "F.Mask" "F.Paste")
			(net "PEX3_P1V25_ADC_ALERT_N")
		)
		(pad "4" smd rect
			(at -1.400048 0.750062 90)
			(size 0.2286 0.6096)
			(layers "F.Cu" "F.Mask" "F.Paste")
			(net "SMB_PEX3_P1V25_ADC_SDA")
		)
		(pad "5" smd rect
			(at -0.750062 1.400048 180)
			(size 0.2286 0.6096)
			(layers "F.Cu" "F.Mask" "F.Paste")
			(net "SMB_PEX3_P1V25_ADC_SCL")
		)
		(pad "6" smd rect
			(at -0.249936 1.400048 180)
			(size 0.2286 0.6096)
			(layers "F.Cu" "F.Mask" "F.Paste")
			(net "Net_8600")
		)
		(pad "7" smd rect
			(at 0.249936 1.400048 180)
			(size 0.2286 0.6096)
			(layers "F.Cu" "F.Mask" "F.Paste")
			(net "Net_8599")
		)
		(pad "8" smd rect
			(at 0.750062 1.400048 180)
			(size 0.2286 0.6096)
			(layers "F.Cu" "F.Mask" "F.Paste")
			(net "Net_8598")
		)
		(pad "9" smd rect
			(at 1.400048 0.750062 90)
			(size 0.2286 0.6096)
			(layers "F.Cu" "F.Mask" "F.Paste")
			(net "P3V3_AUX")
		)
		(pad "10" smd rect
			(at 1.400048 0.249936 90)
			(size 0.2286 0.6096)
			(layers "F.Cu" "F.Mask" "F.Paste")
			(net "GND")
		)
		(pad "11" smd rect
			(at 1.400048 -0.249936 90)
			(size 0.2286 0.6096)
			(layers "F.Cu" "F.Mask" "F.Paste")
			(net "P1V25_PEX3_R")
		)
		(pad "12" smd rect
			(at 1.400048 -0.750062 90)
			(size 0.2286 0.6096)
			(layers "F.Cu" "F.Mask" "F.Paste")
			(net "P12V_PEX3_P1V25_VIN_N")
		)
		(pad "13" smd rect
			(at 0.750062 -1.400048 180)
			(size 0.2286 0.6096)
			(layers "F.Cu" "F.Mask" "F.Paste")
			(net "P12V_PEX3_P1V25_VIN_P")
		)
		(pad "14" smd rect
			(at 0.249936 -1.400048 180)
			(size 0.2286 0.6096)
			(layers "F.Cu" "F.Mask" "F.Paste")
			(net "Net_8597")
		)
		(pad "15" smd rect
			(at -0.249936 -1.400048 180)
			(size 0.2286 0.6096)
			(layers "F.Cu" "F.Mask" "F.Paste")
			(net "Net_8596")
		)
		(pad "16" smd rect
			(at -0.750062 -1.400048 180)
			(size 0.2286 0.6096)
			(layers "F.Cu" "F.Mask" "F.Paste")
			(net "Net_8595")
		)
		(pad "TH" smd rect
			(at 0 0 180)
			(size 1.7018 1.7018)
			(layers "F.Cu" "F.Mask" "F.Paste")
			(net "GND")
		)
		(zone
			(layer "F.Cu")
			(hatch none 0.5)
			(connect_pads
				(clearance 0)
			)
			(min_thickness 0.25)
			(keepout
				(tracks not_allowed)
				(vias allowed)
				(pads allowed)
				(copperpour not_allowed)
				(footprints allowed)
			)
			(placement
				(enabled no)
				(sheetname "")
			)
			(fill
				(thermal_gap 0.5)
				(thermal_bridge_width 0.5)
				(island_removal_mode 0)
			)
			(polygon
				(pts
					(xy 460.112364 -277.88997) (xy 460.112364 -276.870922) (xy 458.023468 -276.870922) (xy 458.023468 -278.959818)
					(xy 460.112364 -278.959818) (xy 460.112364 -277.91537) (xy 459.969616 -277.91537) (xy 459.969616 -278.81707)
					(xy 458.166216 -278.81707) (xy 458.166216 -277.01367) (xy 459.969616 -277.01367) (xy 459.969616 -277.88997)
				)
			)
		)
	)
	(footprint ""
		(layer "F.Cu")
		(at 361.89031 -261.814564 180)
		(property "Reference" "R838"
			(at 0 0 180)
			(layer "F.SilkS")
			(hide yes)
			(effects
				(font
					(size 1.27 1.27)
				)
			)
		)
		(property "Value" ""
			(at 0 0 180)
			(layer "F.Fab")
			(effects
				(font
					(size 1.27 1.27)
				)
			)
		)
		(duplicate_pad_numbers_are_jumpers no)
		(fp_line
			(start 0.7874 0.4064)
			(end -0.7874 0.4064)
			(stroke
				(width 0.1524)
				(type default)
			)
			(layer "F.SilkS")
		)
		(fp_line
			(start 0.7874 -0.4064)
			(end 0.7874 0.4064)
			(stroke
				(width 0.1524)
				(type default)
			)
			(layer "F.SilkS")
		)
		(fp_line
			(start -0.7874 0.4064)
			(end -0.7874 -0.4064)
			(stroke
				(width 0.1524)
				(type default)
			)
			(layer "F.SilkS")
		)
		(fp_line
			(start -0.7874 -0.4064)
			(end 0.7874 -0.4064)
			(stroke
				(width 0.1524)
				(type default)
			)
			(layer "F.SilkS")
		)
		(fp_line
			(start 0.67945 0.3048)
			(end 0.120396 0.3048)
			(stroke
				(width 0.1)
				(type default)
			)
			(layer "F.Fab")
		)
		(fp_line
			(start 0.67945 -0.3048)
			(end 0.67945 0.3048)
			(stroke
				(width 0.1)
				(type default)
			)
			(layer "F.Fab")
		)
		(fp_line
			(start 0.12065 -0.2794)
			(end 0.12065 -0.3048)
			(stroke
				(width 0.1)
				(type default)
			)
			(layer "F.Fab")
		)
		(fp_line
			(start 0.12065 -0.3048)
			(end 0.67945 -0.3048)
			(stroke
				(width 0.1)
				(type default)
			)
			(layer "F.Fab")
		)
		(fp_line
			(start 0.120396 0.3048)
			(end 0.120396 0.2794)
			(stroke
				(width 0.1)
				(type default)
			)
			(layer "F.Fab")
		)
		(fp_line
			(start 0.120396 0.2794)
			(end -0.12065 0.2794)
			(stroke
				(width 0.1)
				(type default)
			)
			(layer "F.Fab")
		)
		(fp_line
			(start -0.12065 0.3048)
			(end -0.67945 0.3048)
			(stroke
				(width 0.1)
				(type default)
			)
			(layer "F.Fab")
		)
		(fp_line
			(start -0.12065 0.2794)
			(end -0.12065 0.3048)
			(stroke
				(width 0.1)
				(type default)
			)
			(layer "F.Fab")
		)
		(fp_line
			(start -0.12065 -0.2794)
			(end 0.12065 -0.2794)
			(stroke
				(width 0.1)
				(type default)
			)
			(layer "F.Fab")
		)
		(fp_line
			(start -0.12065 -0.305054)
			(end -0.12065 -0.2794)
			(stroke
				(width 0.1)
				(type default)
			)
			(layer "F.Fab")
		)
		(fp_line
			(start -0.67945 0.3048)
			(end -0.67945 -0.305054)
			(stroke
				(width 0.1)
				(type default)
			)
			(layer "F.Fab")
		)
		(fp_line
			(start -0.67945 -0.305054)
			(end -0.12065 -0.305054)
			(stroke
				(width 0.1)
				(type default)
			)
			(layer "F.Fab")
		)
		(pad "1" smd circle
			(at -0.40005 0 180)
			(size 0 0)
			(layers "F.Cu" "F.Mask" "F.Paste")
			(net "PWR_EN_PEX_R")
		)
		(pad "2" smd circle
			(at 0.40005 0 180)
			(size 0 0)
			(layers "F.Cu" "F.Mask" "F.Paste")
			(net "FM_P0V8_PEX3_EN_R")
		)
	)
	(footprint ""
		(layer "F.Cu")
		(at 314.861448 -136.20115 180)
		(property "Reference" "C439"
			(at 0 0 180)
			(layer "F.SilkS")
			(hide yes)
			(effects
				(font
					(size 1.27 1.27)
				)
			)
		)
		(property "Value" ""
			(at 0 0 180)
			(layer "F.Fab")
			(effects
				(font
					(size 1.27 1.27)
				)
			)
		)
		(duplicate_pad_numbers_are_jumpers no)
		(fp_line
			(start 0.299974 0.150114)
			(end -0.299974 0.150114)
			(stroke
				(width 0.1)
				(type default)
			)
			(layer "F.Fab")
		)
		(fp_line
			(start 0.299974 -0.150114)
			(end 0.299974 0.150114)
			(stroke
				(width 0.1)
				(type default)
			)
			(layer "F.Fab")
		)
		(fp_line
			(start -0.299974 0.150114)
			(end -0.299974 -0.150114)
			(stroke
				(width 0.1)
				(type default)
			)
			(layer "F.Fab")
		)
		(fp_line
			(start -0.299974 -0.150114)
			(end 0.299974 -0.150114)
			(stroke
				(width 0.1)
				(type default)
			)
			(layer "F.Fab")
		)
		(pad "1" smd rect
			(at -0.2667 0 180)
			(size 0.3048 0.381)
			(layers "F.Cu" "F.Mask" "F.Paste")
			(net "P5E_PEX2_STN0_TX_DP<7>")
		)
		(pad "2" smd rect
			(at 0.2667 0 180)
			(size 0.3048 0.381)
			(layers "F.Cu" "F.Mask" "F.Paste")
			(net "P5E_PEX2_STN0_TX_C_DP<7>")
		)
	)
)
